FILE_TYPE = CONNECTIVITY;
{Allegro Design Entry HDL 17.4-2019 S026 (4007227) 1/17/2022}
"PAGE_NUMBER" = 339;
0"NC";
1"GND\g";
2"GND\g";
3"GND\g";
4"GND\g";
5"P3V3_OCP_SFF_R\g";
6"GND\g";
7"GND\g";
8"GND\g";
9"GND\g";
10"P3V3_AUX\g";
11"GND\g";
12"P3V3_AUX\g";
13"P12V_OCP_SFF\g";
14"P12V_AUX\g";
15"P12V_OCP_AVIN_PD_1";
16"P12V_OCP_OV_FB_1";
17"HP_LVC3_OCP_V3_1_P12V_PWRGD";
18"P12V_OCP_FLTB_1";
19"P12V_OCP_IMON_1";
20"P12V_OCP_EN_1_R2";
21"GND\g";
22"P12V_OCP_TIMER_1";
23"P12V_OCP_ISET_1";
24"P12V_OCP_SS_1";
25"GND\g";
26"GND\g";
27"P3V3_AUX\g";
28"GND\g";
29"GND\g";
30"P12V_AUX\g";
31"GND\g";
32"P12V_OCP_SFF_ISENSE_MPS_TIC";
33"P12V_OCP_SFF_ISENSE_MPS_MAM";
34"P3V3_OCP_MODE_1";
35"P12V_OCP_SFF_BUF_EN_R";
36"P12V_OCP_SFF_BUF_EN_R";
37"P12V_OCP_SFF_EN_R";
38"HP_LVC3_OCP_V3_1_P12V_PWRGD";
39"P3V3_OCP_SFF_EN_R";
40"P12V_OCP_AVIN_PD_1";
41"P3V3_OCP_DVDT_1";
42"P3V3_OCP_GATE_1";
43"P3V3_OCP_ILIMIT_1";
44"P3V3_OCP_EN_1_R2";
%"Q_RES"
"2","(-4025,12275)","0","pure_quanta","I100";
;
LOCATION"PR3844"
$SEC"1"
CDS_SEC"1"
ROOM"NIC_P3V3_BOM2"
MATERIAL"CHIP"
PACK_TYPE"0402LF"
TOLERANCE"1%"
VALUE"71.5K"
CDS_LIB"pure_quanta"
WATTAGE"1/16W"
PART_NUMBER"CS37152FB05";
"A"
$PN"1"34;
"B"
$PN"2"31;
%"UNIVERSAL_GND"
"1","(-3600,11900)","0","pure_quanta_power","I101";
;
CDS_LIB"pure_quanta_power"
HDL_POWER"GND";
"A"1;
%"Q_RES"
"1","(-3600,12225)","1","pure_quanta","I102";
;
LOCATION"PR3846"
$SEC"1"
CDS_SEC"1"
VALUE"1.33K"
MATERIAL"CHIP"
ROOM"NIC_P3V3_BOM2"
TOLERANCE"1%"
PACK_TYPE"0402LF"
WATTAGE"1/16W"
CDS_LIB"pure_quanta"
PART_NUMBER"CS21332FB05";
"B"
$PN"2"43;
"A"
$PN"1"1;
%"UNIVERSAL_GND"
"1","(-3050,11900)","0","pure_quanta_power","I103";
;
CDS_LIB"pure_quanta_power"
HDL_POWER"GND";
"A"2;
%"Q_CAP"
"1","(-3050,12200)","0","pure_quanta","I104";
;
LOCATION"PC2161"
$SEC"1"
CDS_SEC"1"
ROOM"NIC_P3V3_BOM2"
VALUE"0.068UF"
MATERIAL"X7R"
PACK_TYPE"0402"
VOLTAGE"16V"
CDS_LIB"pure_quanta"
TOLERANCE"10%"
PART_NUMBER"CH3683K1B09";
"B"
$PN"2"2;
"A"
$PN"1"41;
%"UNIVERSAL_GND"
"1","(-1550,11775)","0","pure_quanta_power","I105";
;
CDS_LIB"pure_quanta_power"
HDL_POWER"GND";
"A"26;
%"Q_CAP"
"1","(-1550,12125)","0","pure_quanta","I106";
;
LOCATION"PC2162"
$SEC"1"
CDS_SEC"1"
ROOM"NIC_P3V3_BOM2"
PACK_TYPE"0402"
MATERIAL"X7R"
TOLERANCE"5%"
VOLTAGE"50V"
VALUE"100PF"
CDS_LIB"pure_quanta"
PART_NUMBER"CH11006JB18";
"B"
$PN"2"26;
"A"
$PN"1"42;
%"UNIVERSAL_GND"
"1","(-950,12000)","0","pure_quanta_power","I107";
;
CDS_LIB"pure_quanta_power"
HDL_POWER"GND";
"A"3;
%"Q_CAP"
"1","(-950,12350)","0","pure_quanta","I108";
;
LOCATION"PC2163"
$SEC"1"
CDS_SEC"1"
MATERIAL"X6S"
VALUE"10UF"
VOLTAGE"16V"
PACK_TYPE"C0805"
ROOM"NIC_P3V3_BOM2"
TOLERANCE"10%"
CDS_LIB"pure_quanta"
PART_NUMBER"CH6103KEA01";
"B"
$PN"2"3;
"A"
$PN"1"5;
%"UNIVERSAL_GND"
"1","(-3400,12650)","0","pure_quanta_power","I110";
;
CDS_LIB"pure_quanta_power"
HDL_POWER"GND";
"A"4;
%"Q_CAP"
"1","(-3400,12850)","0","pure_quanta","I111";
;
LOCATION"PC2159"
$SEC"1"
CDS_SEC"1"
ROOM"NIC_P3V3_BOM2"
PACK_TYPE"C0402"
VOLTAGE"25V"
VALUE"1UF"
MATERIAL"X6S"
CDS_LIB"pure_quanta"
TOLERANCE"10%"
PART_NUMBER"CH5104KEB02";
"B"
$PN"2"4;
"A"
$PN"1"27;
%"UNIVERSAL_POWER"
"1","(-3325,13225)","2","pure_quanta_power","I112";
;
HDL_POWER"P3V3_AUX"
CDS_LIB"pure_quanta_power";
"A"27;
%"MP5016GQHLZ"
"1","(-2400,12525)","0","pure_quanta","I113";
;
LOCATION"PU205"
$SEC"1"
CDS_SEC"1"
PART_TYPE"SMLF"
VALUE"MP5016GQH-L-Z"
ROOM"NIC_P3V3_BOM2"
MATERIAL"IC"
CDS_LIB"pure_quanta"
CDS_LMAN_SYM_OUTLINE"-250,200,250,-200"
NEEDS_NO_SIZE"TRUE"
PART_NUMBER"AL005016007";
"SOURCE"
$PN"6_7"5;
"GATE"
$PN"8"42;
"DV_DT"
$PN"10"41;
"VCC"
$PN"1_2"27;
"GND"
$PN"3"26;
"ILIMIT"
$PN"4"43;
"MODE"
$PN"5"34;
"EN"
$PN"9"44;
%"UNIVERSAL_POWER"
"1","(-950,13000)","2","pure_quanta_power","I114";
;
HDL_POWER"P3V3_OCP_SFF_R"
CDS_LIB"pure_quanta_power";
"A"5;
%"Q_RES"
"1","(-7725,9600)","0","pure_quanta","I128";
;
LOCATION"R3834"
$SEC"1"
CDS_SEC"1"
MATERIAL"EMPTY"
TOLERANCE"5%"
VALUE"0"
ROOM"NIC_P12V_MPS_MAM_BOM2"
PACK_TYPE"0402LF"
WATTAGE"1/16W"
CDS_LIB"pure_quanta"
PART_NUMBER"CS00002JB13";
"B"
$PN"2"20;
"A"
$PN"1"37;
%"Q_RES"
"1","(-7825,9975)","0","pure_quanta","I130";
;
LOCATION"R591"
$SEC"1"
CDS_SEC"1"
VALUE"0"
TOLERANCE"5%"
MATERIAL"CHIP"
ROOM"NIC_P12V_MPS_MAM_BOM2"
WATTAGE"1/16W"
PACK_TYPE"0402LF"
CDS_LIB"pure_quanta"
PART_NUMBER"CS00002JB13";
"B"
$PN"2"20;
"A"
$PN"1"35;
%"Q_RES"
"1","(-3850,12575)","0","pure_quanta","I131";
;
LOCATION"R3845"
$SEC"1"
CDS_SEC"1"
PACK_TYPE"0402LF"
MATERIAL"EMPTY"
ROOM"NIC_P3V3_BOM2"
TOLERANCE"5%"
VALUE"0"
CDS_LIB"pure_quanta"
WATTAGE"1/16W"
PART_NUMBER"CS00002JB13";
"B"
$PN"2"44;
"A"
$PN"1"39;
%"Q_RES"
"1","(-4000,13325)","0","pure_quanta","I134";
;
LOCATION"R1487"
$SEC"1"
CDS_SEC"1"
MATERIAL"CHIP"
VALUE"0"
TOLERANCE"5%"
ROOM"NIC_P3V3_BOM2"
CDS_LIB"pure_quanta"
WATTAGE"1/16W"
PACK_TYPE"0402LF"
PART_NUMBER"CS00002JB13";
"B"
$PN"2"44;
"A"
$PN"1"36;
%"Q_RES"
"1","(-4025,12900)","0","pure_quanta","I135";
;
LOCATION"R1137"
$SEC"1"
CDS_SEC"1"
ROOM"NIC_P3V3_BOM2"
TOLERANCE"5%"
PACK_TYPE"0402LF"
MATERIAL"EMPTY"
VALUE"0"
WATTAGE"1/16W"
CDS_LIB"pure_quanta"
PART_NUMBER"CS00002JB13";
"B"
$PN"2"44;
"A"
$PN"1"38;
%"RS31312R"
"1","(-6400,9475)","0","pure_quanta","I137";
;
LOCATION"PU204"
SEC"1"
VALUE"RS31312R"
MATERIAL"IC"
PART_TYPE"SMLF"
ROOM"NIC_P12V_MPS_MAM_BOM2"
CDS_LMAN_SYM_OUTLINE"-250,525,250,-525"
NEEDS_NO_SIZE"TRUE"
CDS_LIB"pure_quanta"
SEC_TYPE""
PART_NUMBER"AL031312000";
"GND"
$PN"7"25;
"SS"
$PN"6"24;
"ISET"
$PN"5"23;
"TIMER"
$PN"4"22;
"ENTM"
$PN"3"21;
"LOADEN"
$PN"2"21;
"EN"
$PN"1"20;
"VIN_26"
$PN"26"14;
"VIN_25"
$PN"25"14;
"VIN_24"
$PN"24"14;
"VIN_23"
$PN"23"14;
"IMON"
$PN"8"19;
"FLTB"
$PN"9"18;
"PG"
$PN"10"17;
"OV"
$PN"11"16;
"VOUT_13"
$PN"13"13;
"AVIN"
$PN"12"15;
"VOUT_14"
$PN"14"13;
"VOUT_15"
$PN"15"13;
"VOUT_16"
$PN"16"13;
"VOUT_17"
$PN"17"13;
"VOUT_18"
$PN"18"13;
"VOUT_19"
$PN"19"13;
"VIN_21_22"
$PN"21_22"14;
"VOUT_20"
$PN"20"13;
%"GND"
"1","(-8025,8800)","0","pure_quanta_power","I59";
;
CDS_LIB"pure_quanta_power"
SIZE"1B"
HDL_POWER"GND";
"A<SIZE-1..0>\NAC"6;
%"Q_CAP"
"1","(-8025,9150)","0","pure_quanta","I60";
;
LOCATION"PC2153"
$SEC"1"
CDS_SEC"1"
PACK_TYPE"0402"
VALUE"0.22UF"
VOLTAGE"16V"
MATERIAL"X7R"
ROOM"NIC_P12V_MPS_MAM_BOM2"
TOLERANCE"10%"
CDS_LIB"pure_quanta"
PART_NUMBER"CH4223K1B00";
"B"
$PN"2"6;
"A"
$PN"1"22;
%"GND"
"1","(-7600,8725)","0","pure_quanta_power","I61";
;
CDS_LIB"pure_quanta_power"
SIZE"1B"
HDL_POWER"GND";
"A<SIZE-1..0>\NAC"7;
%"GND"
"1","(-7200,8700)","0","pure_quanta_power","I62";
;
CDS_LIB"pure_quanta_power"
SIZE"1B"
HDL_POWER"GND";
"A<SIZE-1..0>\NAC"8;
%"Q_RES"
"2","(-7600,9025)","0","pure_quanta","I63";
;
LOCATION"PR3835"
$SEC"1"
CDS_SEC"1"
ROOM"NIC_P12V_MPS_MAM_BOM2"
WATTAGE"1/16W"
PACK_TYPE"0402LF"
TOLERANCE"1%"
VALUE"14.3K"
MATERIAL"CHIP"
CDS_LIB"pure_quanta"
PART_NUMBER"CS31432FB02";
"A"
$PN"1"23;
"B"
$PN"2"7;
%"Q_CAP"
"1","(-7200,8925)","0","pure_quanta","I64";
;
LOCATION"PC2155"
$SEC"1"
CDS_SEC"1"
PACK_TYPE"C0402"
VOLTAGE"25V"
MATERIAL"X7R"
VALUE"0.047UF"
ROOM"NIC_P12V_MPS_MAM_BOM2"
TOLERANCE"10%"
CDS_LIB"pure_quanta"
PART_NUMBER"CH3474K1B04";
"B"
$PN"2"8;
"A"
$PN"1"24;
%"GND"
"1","(-7600,9350)","0","pure_quanta_power","I66";
;
SIZE"1B"
CDS_LIB"pure_quanta_power"
HDL_POWER"GND";
"A<SIZE-1..0>\NAC"21;
%"GND"
"1","(-7275,9775)","0","pure_quanta_power","I67";
;
CDS_LIB"pure_quanta_power"
SIZE"1B"
HDL_POWER"GND";
"A<SIZE-1..0>\NAC"9;
%"Q_CAP"
"1","(-7275,10000)","0","pure_quanta","I68";
;
LOCATION"PC2154"
$SEC"1"
CDS_SEC"1"
VALUE"1UF"
MATERIAL"X6S"
VOLTAGE"25V"
PACK_TYPE"C0402"
ROOM"NIC_P12V_MPS_MAM_BOM2"
TOLERANCE"10%"
CDS_LIB"pure_quanta"
PART_NUMBER"CH5104KEB02";
"B"
$PN"2"9;
"A"
$PN"1"14;
%"UNIVERSAL_POWER"
"1","(-7275,10350)","0","pure_quanta_power","I69";
;
HDL_POWER"P12V_AUX"
CDS_LIB"pure_quanta_power";
"A"14;
%"GND"
"1","(-6859,8866)","0","pure_quanta_power","I70";
;
CDS_LIB"pure_quanta_power"
SIZE"1B"
HDL_POWER"GND";
"A<SIZE-1..0>\NAC"25;
%"Q_RES"
"2","(-5775,8725)","0","pure_quanta","I71";
;
LOCATION"PR3837"
$SEC"1"
CDS_SEC"1"
WATTAGE"1/16W"
PACK_TYPE"0402LF"
VALUE"17.4K"
TOLERANCE"1%"
MATERIAL"CHIP"
ROOM"NIC_P12V_MPS_MAM_BOM2"
CDS_LIB"pure_quanta"
PART_NUMBER"CS31742FB04";
"A"
$PN"1"19;
"B"
$PN"2"28;
%"GND"
"1","(-5325,8325)","0","pure_quanta_power","I72";
;
SIZE"1B"
CDS_LIB"pure_quanta_power"
HDL_POWER"GND";
"A<SIZE-1..0>\NAC"28;
%"Q_CAP"
"1","(-5325,8725)","0","pure_quanta","I73";
;
LOCATION"PC2156"
$SEC"1"
CDS_SEC"1"
VOLTAGE"50V"
PACK_TYPE"C0402"
MATERIAL"X7R"
ROOM"NIC_P12V_MPS_MAM_BOM2"
VALUE"100NF"
TOLERANCE"10%"
CDS_LIB"pure_quanta"
PART_NUMBER"CH4106K1B01";
"B"
$PN"2"28;
"A"
$PN"1"19;
%"Q_RES"
"1","(-5400,9100)","0","pure_quanta","I74";
;
LOCATION"PR3839"
$SEC"1"
CDS_SEC"1"
MATERIAL"CHIP"
TOLERANCE"1%"
VALUE"10K"
PACK_TYPE"0402LF"
ROOM"NIC_P12V_MPS_MAM_BOM2"
WATTAGE"1/16W"
CDS_LIB"pure_quanta"
PART_NUMBER"CS31002FB08";
"B"
$PN"2"12;
"A"
$PN"1"18;
%"Q_RES"
"2","(-5925,10175)","0","pure_quanta","I75";
;
LOCATION"R4532"
$SEC"1"
CDS_SEC"1"
ROOM"NIC_P12V_MPS_MAM_BOM2"
TOLERANCE"1%"
MATERIAL"CHIP"
WATTAGE"1/16W"
VALUE"10K"
PACK_TYPE"0402LF"
CDS_LIB"pure_quanta"
PART_NUMBER"CS31002FB08";
"A"
$PN"1"10;
"B"
$PN"2"17;
%"Q_RES"
"2","(-5400,9575)","0","pure_quanta","I76";
;
LOCATION"PR3838"
$SEC"1"
CDS_SEC"1"
WATTAGE"1/16W"
TOLERANCE"1%"
VALUE"100"
MATERIAL"EMPTY"
PACK_TYPE"0402LF"
ROOM"NIC_P12V_MPS_MAM_BOM2"
CDS_LIB"pure_quanta"
PART_NUMBER"CS11002FB07";
"A"
$PN"1"13;
"B"
$PN"2"15;
%"GND"
"1","(-4200,8750)","0","pure_quanta_power","I79";
;
SIZE"1B"
CDS_LIB"pure_quanta_power"
HDL_POWER"GND";
"A<SIZE-1..0>\NAC"29;
%"Q_RES"
"2","(-4400,9075)","0","pure_quanta","I80";
;
LOCATION"PR3842"
$SEC"1"
CDS_SEC"1"
ROOM"NIC_P12V_MPS_MAM_BOM2"
VALUE"10K"
MATERIAL"CHIP"
TOLERANCE"1%"
WATTAGE"1/16W"
PACK_TYPE"0402LF"
CDS_LIB"pure_quanta"
PART_NUMBER"CS31002FB08";
"A"
$PN"1"16;
"B"
$PN"2"29;
%"Q_RES"
"2","(-4800,9575)","0","pure_quanta","I81";
;
LOCATION"PR3840"
$SEC"1"
CDS_SEC"1"
MATERIAL"EMPTY"
VALUE"71.5K"
ROOM"NIC_P12V_MPS_MAM_BOM2"
TOLERANCE"1%"
PACK_TYPE"0402LF"
CDS_LIB"pure_quanta"
WATTAGE"1/16W"
PART_NUMBER"CS37152FB05";
"A"
$PN"1"13;
"B"
$PN"2"16;
%"Q_RES"
"2","(-4400,9500)","0","pure_quanta","I82";
;
LOCATION"PR3841"
$SEC"1"
CDS_SEC"1"
VALUE"120K"
WATTAGE"1/16W"
ROOM"NIC_P12V_MPS_MAM_BOM2"
PACK_TYPE"0402LF"
MATERIAL"CHIP"
TOLERANCE"1%"
CDS_LIB"pure_quanta"
PART_NUMBER"CS41202FB05";
"A"
$PN"1"30;
"B"
$PN"2"16;
%"VCCAUX15"
"1","(-5925,10375)","0","pure_quanta_power","I83";
;
HDL_POWER"P3V3_AUX"
CDS_LIB"pure_quanta_power";
"A"10;
%"Q_RES"
"1","(-3975,8400)","0","pure_quanta","I84";
;
LOCATION"R3872"
$SEC"1"
CDS_SEC"1"
ROOM"NIC_P12V_MPS_TIC_BOM3"
TOLERANCE"5%"
PACK_TYPE"0402LF"
MATERIAL"EMPTY"
VALUE"0"
WATTAGE"1/16W"
CDS_LIB"pure_quanta"
PART_NUMBER"CS00002JB13";
"B"
$PN"2"32;
"A"
$PN"1"19;
%"Q_RES"
"1","(-3975,8575)","0","pure_quanta","I85";
;
LOCATION"R3871"
$SEC"1"
CDS_SEC"1"
TOLERANCE"5%"
PACK_TYPE"0402LF"
ROOM"NIC_P12V_MPS_MAM_BOM2"
MATERIAL"CHIP"
WATTAGE"1/16W"
VALUE"0"
CDS_LIB"pure_quanta"
PART_NUMBER"CS00002JB13";
"B"
$PN"2"33;
"A"
$PN"1"19;
%"Q_CAP"
"1","(-3875,9075)","0","pure_quanta","I86";
;
LOCATION"PC2158"
$SEC"1"
CDS_SEC"1"
ROOM"NIC_P12V_MPS_MAM_BOM2"
MATERIAL"X7R"
TOLERANCE"20%"
VOLTAGE"16V"
VALUE"2.2UF"
PACK_TYPE"C0603"
CDS_LIB"pure_quanta"
PART_NUMBER"CH5223M1900";
"B"
$PN"2"29;
"A"
$PN"1"40;
%"Q_RES"
"2","(-3875,9500)","0","pure_quanta","I88";
;
LOCATION"PR3843"
$SEC"1"
CDS_SEC"1"
TOLERANCE"1%"
VALUE"49.9"
PACK_TYPE"0603LF"
MATERIAL"CHIP"
WATTAGE"1/10W"
ROOM"NIC_P12V_MPS_MAM_BOM2"
CDS_LIB"pure_quanta"
PART_NUMBER"CS04993F909";
"A"
$PN"1"30;
"B"
$PN"2"40;
%"UNIVERSAL_POWER"
"1","(-3875,9800)","0","pure_quanta_power","I89";
;
HDL_POWER"P12V_AUX"
CDS_LIB"pure_quanta_power";
"A"30;
%"GND"
"1","(-3525,9750)","0","pure_quanta_power","I90";
;
SIZE"1B"
CDS_LIB"pure_quanta_power"
HDL_POWER"GND";
"A<SIZE-1..0>\NAC"11;
%"Q_CAP"
"1","(-3525,9925)","2","pure_quanta","I91";
;
LOCATION"PC2160"
$SEC"1"
CDS_SEC"1"
VOLTAGE"25V"
ROOM"NIC_P12V_MPS_MAM_BOM2"
VALUE"0.1UF"
TOLERANCE"10%"
MATERIAL"X7R"
PACK_TYPE"0402"
CDS_LIB"pure_quanta"
PART_NUMBER"CH4104K1B00";
"B"
$PN"2"11;
"A"
$PN"1"13;
%"UNIVERSAL_POWER"
"1","(-3525,10200)","2","pure_quanta_power","I92";
;
HDL_POWER"P12V_OCP_SFF"
CDS_LIB"pure_quanta_power";
"A"13;
%"VCCAUX15"
"1","(-4775,9150)","0","pure_quanta_power","I95";
;
HDL_POWER"P3V3_AUX"
CDS_LIB"pure_quanta_power";
"A"12;
%"UNIVERSAL_GND"
"1","(-4450,11900)","0","pure_quanta_power","I97";
;
CDS_LIB"pure_quanta_power"
HDL_POWER"GND";
"A"31;
%"Q_CAP"
"1","(-4450,12275)","0","pure_quanta","I98";
;
LOCATION"PC2157"
$SEC"1"
CDS_SEC"1"
PACK_TYPE"0402"
MATERIAL"NPO"
ROOM"NIC_P3V3_BOM2"
VALUE"39PF"
VOLTAGE"50V"
CDS_LIB"pure_quanta"
TOLERANCE"5%"
PART_NUMBER"CH03906JB06";
"B"
$PN"2"31;
"A"
$PN"1"34;
END.
